FILE_TYPE = CONNECTIVITY;
{Allegro Design Entry HDL 16.6-p007 (v16-6-112F) 10/10/2012}
"PAGE_NUMBER" = 67;
0"NC";
1"UPI_CPU1_CPU0_P0P0_DP<19..0>";
2"UPI_CPU1_CPU0_P0P0_DN<19..0>";
3"UPI_CPU0_CPU1_P0P0_DP<19..0>";
4"UPI_CPU0_CPU1_P0P0_DN<19..0>";
5"UPI_CPU1_CPU0_P0P0_DN<12>";
6"UPI_CPU0_CPU1_P0P0_DN<19>";
7"UPI_CPU0_CPU1_P0P0_DN<6>";
8"UPI_CPU0_CPU1_P0P0_DN<8>";
9"UPI_CPU0_CPU1_P0P0_DN<7>";
10"UPI_CPU0_CPU1_P0P0_DP<0>";
11"UPI_CPU0_CPU1_P0P0_DN<1>";
12"UPI_CPU0_CPU1_P0P0_DN<2>";
13"UPI_CPU0_CPU1_P0P0_DP<3>";
14"UPI_CPU0_CPU1_P0P0_DP<4>";
15"UPI_CPU0_CPU1_P0P0_DP<5>";
16"UPI_CPU0_CPU1_P0P0_DP<6>";
17"UPI_CPU0_CPU1_P0P0_DP<7>";
18"UPI_CPU0_CPU1_P0P0_DP<8>";
19"UPI_CPU0_CPU1_P0P0_DP<9>";
20"UPI_CPU0_CPU1_P0P0_DN<0>";
21"UPI_CPU0_CPU1_P0P0_DP<1>";
22"UPI_CPU0_CPU1_P0P0_DP<2>";
23"UPI_CPU0_CPU1_P0P0_DN<3>";
24"UPI_CPU0_CPU1_P0P0_DN<4>";
25"UPI_CPU0_CPU1_P0P0_DN<5>";
26"UPI_CPU0_CPU1_P0P0_DN<9>";
27"UPI_CPU0_CPU1_P0P0_DP<10>";
28"UPI_CPU0_CPU1_P0P0_DN<11>";
29"UPI_CPU0_CPU1_P0P0_DP<12>";
30"UPI_CPU0_CPU1_P0P0_DP<13>";
31"UPI_CPU0_CPU1_P0P0_DN<14>";
32"UPI_CPU0_CPU1_P0P0_DP<15>";
33"UPI_CPU0_CPU1_P0P0_DP<16>";
34"UPI_CPU0_CPU1_P0P0_DP<17>";
35"UPI_CPU0_CPU1_P0P0_DN<18>";
36"UPI_CPU0_CPU1_P0P0_DN<10>";
37"UPI_CPU0_CPU1_P0P0_DP<11>";
38"UPI_CPU0_CPU1_P0P0_DN<12>";
39"UPI_CPU0_CPU1_P0P0_DN<13>";
40"UPI_CPU0_CPU1_P0P0_DP<14>";
41"UPI_CPU0_CPU1_P0P0_DN<15>";
42"UPI_CPU0_CPU1_P0P0_DN<16>";
43"UPI_CPU0_CPU1_P0P0_DN<17>";
44"UPI_CPU0_CPU1_P0P0_DP<18>";
45"UPI_CPU0_CPU1_P0P0_DP<19>";
46"UPI_CPU1_CPU0_P0P0_DP<0>";
47"UPI_CPU1_CPU0_P0P0_DP<1>";
48"UPI_CPU1_CPU0_P0P0_DN<2>";
49"UPI_CPU1_CPU0_P0P0_DN<3>";
50"UPI_CPU1_CPU0_P0P0_DN<4>";
51"UPI_CPU1_CPU0_P0P0_DP<5>";
52"UPI_CPU1_CPU0_P0P0_DN<6>";
53"UPI_CPU1_CPU0_P0P0_DN<7>";
54"UPI_CPU1_CPU0_P0P0_DP<8>";
55"UPI_CPU1_CPU0_P0P0_DN<9>";
56"UPI_CPU1_CPU0_P0P0_DN<0>";
57"UPI_CPU1_CPU0_P0P0_DN<1>";
58"UPI_CPU1_CPU0_P0P0_DP<2>";
59"UPI_CPU1_CPU0_P0P0_DP<3>";
60"UPI_CPU1_CPU0_P0P0_DP<4>";
61"UPI_CPU1_CPU0_P0P0_DN<5>";
62"UPI_CPU1_CPU0_P0P0_DP<6>";
63"UPI_CPU1_CPU0_P0P0_DP<7>";
64"UPI_CPU1_CPU0_P0P0_DN<8>";
65"UPI_CPU1_CPU0_P0P0_DP<9>";
66"UPI_CPU1_CPU0_P0P0_DN<10>";
67"UPI_CPU1_CPU0_P0P0_DN<11>";
68"UPI_CPU1_CPU0_P0P0_DN<13>";
69"UPI_CPU1_CPU0_P0P0_DN<14>";
70"UPI_CPU1_CPU0_P0P0_DN<15>";
71"UPI_CPU1_CPU0_P0P0_DN<16>";
72"UPI_CPU1_CPU0_P0P0_DP<17>";
73"UPI_CPU1_CPU0_P0P0_DP<18>";
74"UPI_CPU1_CPU0_P0P0_DN<19>";
75"UPI_CPU1_CPU0_P0P0_DP<10>";
76"UPI_CPU1_CPU0_P0P0_DP<11>";
77"UPI_CPU1_CPU0_P0P0_DP<12>";
78"UPI_CPU1_CPU0_P0P0_DP<13>";
79"UPI_CPU1_CPU0_P0P0_DP<14>";
80"UPI_CPU1_CPU0_P0P0_DP<15>";
81"UPI_CPU1_CPU0_P0P0_DP<16>";
82"UPI_CPU1_CPU0_P0P0_DN<17>";
83"UPI_CPU1_CPU0_P0P0_DN<18>";
84"UPI_CPU1_CPU0_P0P0_DP<19>";
%"TAP"
"1","(-5225,2125)","2","mstr_standard","I100";
;
CDS_LIB"mstr_standard"
BODY_TYPE"PLUMBING"
HDL_TAP"TRUE";
"B \NAC \NWC"3;
"S \NAC"
BN"11"37;
%"TAP"
"1","(-5225,2025)","2","mstr_standard","I101";
;
CDS_LIB"mstr_standard"
BODY_TYPE"PLUMBING"
HDL_TAP"TRUE";
"B \NAC \NWC"3;
"S \NAC"
BN"9"19;
%"TAP"
"1","(-5225,1975)","2","mstr_standard","I102";
;
CDS_LIB"mstr_standard"
BODY_TYPE"PLUMBING"
HDL_TAP"TRUE";
"B \NAC \NWC"3;
"S \NAC"
BN"8"18;
%"TAP"
"1","(-5225,1925)","2","mstr_standard","I103";
;
CDS_LIB"mstr_standard"
BODY_TYPE"PLUMBING"
HDL_TAP"TRUE";
"B \NAC \NWC"3;
"S \NAC"
BN"7"17;
%"TAP"
"1","(-5225,1875)","2","mstr_standard","I104";
;
CDS_LIB"mstr_standard"
BODY_TYPE"PLUMBING"
HDL_TAP"TRUE";
"B \NAC \NWC"3;
"S \NAC"
BN"6"16;
%"TAP"
"1","(-5225,1825)","2","mstr_standard","I105";
;
CDS_LIB"mstr_standard"
BODY_TYPE"PLUMBING"
HDL_TAP"TRUE";
"B \NAC \NWC"3;
"S \NAC"
BN"5"15;
%"TAP"
"1","(-5225,2675)","2","mstr_standard","I106";
;
CDS_LIB"mstr_standard"
BODY_TYPE"PLUMBING"
HDL_TAP"TRUE";
"B \NAC \NWC"3;
"S \NAC"
BN"1"21;
%"TAP"
"1","(-5225,1575)","2","mstr_standard","I107";
;
CDS_LIB"mstr_standard"
BODY_TYPE"PLUMBING"
HDL_TAP"TRUE";
"B \NAC \NWC"3;
"S \NAC"
BN"0"10;
%"TAP"
"1","(-5225,3275)","2","mstr_standard","I108";
;
CDS_LIB"mstr_standard"
BODY_TYPE"PLUMBING"
HDL_TAP"TRUE";
"B \NAC \NWC"3;
"S \NAC"
BN"13"30;
%"TAP"
"1","(-2575,3575)","0","mstr_standard","I109";
;
CDS_LIB"mstr_standard"
BODY_TYPE"PLUMBING"
HDL_TAP"TRUE";
"B \NAC \NWC"2;
"S \NAC"
BN"19"74;
%"TAP"
"1","(-2575,3425)","0","mstr_standard","I110";
;
CDS_LIB"mstr_standard"
BODY_TYPE"PLUMBING"
HDL_TAP"TRUE";
"B \NAC \NWC"2;
"S \NAC"
BN"16"71;
%"TAP"
"1","(-2575,3375)","0","mstr_standard","I111";
;
CDS_LIB"mstr_standard"
BODY_TYPE"PLUMBING"
HDL_TAP"TRUE";
"B \NAC \NWC"2;
"S \NAC"
BN"15"70;
%"TAP"
"1","(-2575,3275)","0","mstr_standard","I112";
;
CDS_LIB"mstr_standard"
BODY_TYPE"PLUMBING"
HDL_TAP"TRUE";
"B \NAC \NWC"2;
"S \NAC"
BN"13"68;
%"TAP"
"1","(-2575,3225)","0","mstr_standard","I113";
;
CDS_LIB"mstr_standard"
BODY_TYPE"PLUMBING"
HDL_TAP"TRUE";
"B \NAC \NWC"2;
"S \NAC"
BN"12"5;
%"TAP"
"1","(-2575,3175)","0","mstr_standard","I114";
;
CDS_LIB"mstr_standard"
BODY_TYPE"PLUMBING"
HDL_TAP"TRUE";
"B \NAC \NWC"2;
"S \NAC"
BN"11"67;
%"TAP"
"1","(-2575,3025)","0","mstr_standard","I115";
;
CDS_LIB"mstr_standard"
BODY_TYPE"PLUMBING"
HDL_TAP"TRUE";
"B \NAC \NWC"2;
"S \NAC"
BN"8"64;
%"TAP"
"1","(-2575,1875)","0","mstr_standard","I116";
;
CDS_LIB"mstr_standard"
BODY_TYPE"PLUMBING"
HDL_TAP"TRUE";
"B \NAC \NWC"2;
"S \NAC"
BN"6"52;
%"TAP"
"1","(-2575,1775)","0","mstr_standard","I117";
;
CDS_LIB"mstr_standard"
BODY_TYPE"PLUMBING"
HDL_TAP"TRUE";
"B \NAC \NWC"2;
"S \NAC"
BN"4"50;
%"TAP"
"1","(-2575,2675)","0","mstr_standard","I118";
;
CDS_LIB"mstr_standard"
BODY_TYPE"PLUMBING"
HDL_TAP"TRUE";
"B \NAC \NWC"2;
"S \NAC"
BN"1"57;
%"TAP"
"1","(-2575,2625)","0","mstr_standard","I119";
;
CDS_LIB"mstr_standard"
BODY_TYPE"PLUMBING"
HDL_TAP"TRUE";
"B \NAC \NWC"2;
"S \NAC"
BN"0"56;
%"TAP"
"1","(-2900,2525)","0","mstr_standard","I120";
;
CDS_LIB"mstr_standard"
BODY_TYPE"PLUMBING"
HDL_TAP"TRUE";
"B \NAC \NWC"1;
"S \NAC"
BN"19"84;
%"TAP"
"1","(-2900,2375)","0","mstr_standard","I121";
;
CDS_LIB"mstr_standard"
BODY_TYPE"PLUMBING"
HDL_TAP"TRUE";
"B \NAC \NWC"1;
"S \NAC"
BN"16"81;
%"TAP"
"1","(-2900,2325)","0","mstr_standard","I122";
;
CDS_LIB"mstr_standard"
BODY_TYPE"PLUMBING"
HDL_TAP"TRUE";
"B \NAC \NWC"1;
"S \NAC"
BN"15"80;
%"TAP"
"1","(-2900,2225)","0","mstr_standard","I123";
;
CDS_LIB"mstr_standard"
BODY_TYPE"PLUMBING"
HDL_TAP"TRUE";
"B \NAC \NWC"1;
"S \NAC"
BN"13"78;
%"TAP"
"1","(-2900,2175)","0","mstr_standard","I124";
;
CDS_LIB"mstr_standard"
BODY_TYPE"PLUMBING"
HDL_TAP"TRUE";
"B \NAC \NWC"1;
"S \NAC"
BN"12"77;
%"TAP"
"1","(-2900,2125)","0","mstr_standard","I125";
;
CDS_LIB"mstr_standard"
BODY_TYPE"PLUMBING"
HDL_TAP"TRUE";
"B \NAC \NWC"1;
"S \NAC"
BN"11"76;
%"TAP"
"1","(-2900,1975)","0","mstr_standard","I126";
;
CDS_LIB"mstr_standard"
BODY_TYPE"PLUMBING"
HDL_TAP"TRUE";
"B \NAC \NWC"1;
"S \NAC"
BN"8"54;
%"TAP"
"1","(-2900,2925)","0","mstr_standard","I127";
;
CDS_LIB"mstr_standard"
BODY_TYPE"PLUMBING"
HDL_TAP"TRUE";
"B \NAC \NWC"1;
"S \NAC"
BN"6"62;
%"TAP"
"1","(-2900,2825)","0","mstr_standard","I128";
;
CDS_LIB"mstr_standard"
BODY_TYPE"PLUMBING"
HDL_TAP"TRUE";
"B \NAC \NWC"1;
"S \NAC"
BN"4"60;
%"TAP"
"1","(-2900,1625)","0","mstr_standard","I129";
;
CDS_LIB"mstr_standard"
BODY_TYPE"PLUMBING"
HDL_TAP"TRUE";
"B \NAC \NWC"1;
"S \NAC"
BN"1"47;
%"TAP"
"1","(-2900,1575)","0","mstr_standard","I130";
;
CDS_LIB"mstr_standard"
BODY_TYPE"PLUMBING"
HDL_TAP"TRUE";
"B \NAC \NWC"1;
"S \NAC"
BN"0"46;
%"TAP"
"1","(-5500,1625)","2","mstr_standard","I131";
;
CDS_LIB"mstr_standard"
BODY_TYPE"PLUMBING"
HDL_TAP"TRUE";
"B \NAC \NWC"4;
"S \NAC"
BN"1"11;
%"SKX_EXT_B"
"13","(-4050,2575)","0","chpset_lib","I132";
;
CDS_SEC"13"
LOCATION"U2D1"
PART_NUMBER"TBD"
MATERIAL"IC"
PACK_TYPE"BGA1"
SEC_TYPE"BGA1"
CDS_LIB"chpset_lib"
SEC"13"
CDS_LOCATION"U2D1";
"UPI0_TX_DP<0>"
$PN"M1"56;
"UPI0_TX_DP<1>"
$PN"T1"57;
"UPI0_TX_DP<2>"
$PN"Y3"58;
"UPI0_TX_DP<3>"
$PN"W2"59;
"UPI0_TX_DP<4>"
$PN"AA2"60;
"UPI0_TX_DP<5>"
$PN"AD1"61;
"UPI0_TX_DP<6>"
$PN"AF3"62;
"UPI0_TX_DP<7>"
$PN"AG2"63;
"UPI0_TX_DP<8>"
$PN"AJ2"64;
"UPI0_TX_DP<9>"
$PN"AK1"65;
"UPI0_TX_DP<10>"
$PN"AK3"66;
"UPI0_TX_DP<11>"
$PN"AP3"67;
"UPI0_TX_DP<12>"
$PN"AP1"5;
"UPI0_TX_DP<13>"
$PN"AR2"68;
"UPI0_TX_DP<14>"
$PN"AR4"69;
"UPI0_TX_DP<15>"
$PN"AW4"70;
"UPI0_TX_DP<16>"
$PN"AY3"71;
"UPI0_TX_DP<17>"
$PN"BC2"72;
"UPI0_TX_DP<18>"
$PN"BD3"73;
"UPI0_TX_DP<19>"
$PN"BH3"74;
"UPI0_TX_DN<0>"
$PN"N2"46;
"UPI0_TX_DN<1>"
$PN"P1"47;
"UPI0_TX_DN<2>"
$PN"V3"48;
"UPI0_TX_DN<3>"
$PN"Y1"49;
"UPI0_TX_DN<4>"
$PN"AB3"50;
"UPI0_TX_DN<5>"
$PN"AC2"51;
"UPI0_TX_DN<6>"
$PN"AG4"52;
"UPI0_TX_DN<7>"
$PN"AE2"53;
"UPI0_TX_DN<8>"
$PN"AH3"54;
"UPI0_TX_DN<9>"
$PN"AL2"55;
"UPI0_TX_DN<10>"
$PN"AM3"75;
"UPI0_TX_DN<11>"
$PN"AN4"76;
"UPI0_TX_DN<12>"
$PN"AT1"77;
"UPI0_TX_DN<13>"
$PN"AT3"78;
"UPI0_TX_DN<14>"
$PN"AU4"79;
"UPI0_TX_DN<15>"
$PN"AV5"80;
"UPI0_TX_DN<16>"
$PN"BA4"81;
"UPI0_TX_DN<17>"
$PN"BB3"82;
"UPI0_TX_DN<18>"
$PN"BF3"83;
"UPI0_TX_DN<19>"
$PN"BG4"84;
"UPI0_RX_DP<0>"
$PN"AB9"20;
"UPI0_RX_DP<1>"
$PN"AC8"21;
"UPI0_RX_DP<2>"
$PN"AA6"22;
"UPI0_RX_DP<3>"
$PN"AC6"23;
"UPI0_RX_DP<4>"
$PN"AG6"24;
"UPI0_RX_DP<5>"
$PN"AF7"25;
"UPI0_RX_DP<6>"
$PN"AH7"7;
"UPI0_RX_DP<7>"
$PN"AK5"9;
"UPI0_RX_DP<8>"
$PN"AM7"8;
"UPI0_RX_DP<9>"
$PN"AL8"26;
"UPI0_RX_DP<10>"
$PN"AN8"27;
"UPI0_RX_DP<11>"
$PN"AU8"28;
"UPI0_RX_DP<12>"
$PN"AT9"29;
"UPI0_RX_DP<13>"
$PN"AY7"30;
"UPI0_RX_DP<14>"
$PN"BB7"31;
"UPI0_RX_DP<15>"
$PN"BF7"32;
"UPI0_RX_DP<16>"
$PN"AV9"33;
"UPI0_RX_DP<17>"
$PN"BB9"34;
"UPI0_RX_DP<18>"
$PN"BC10"35;
"UPI0_RX_DP<19>"
$PN"BA10"6;
"UPI0_RX_DN<0>"
$PN"AC10"10;
"UPI0_RX_DN<1>"
$PN"AA8"11;
"UPI0_RX_DN<2>"
$PN"AB7"12;
"UPI0_RX_DN<3>"
$PN"AD5"13;
"UPI0_RX_DN<4>"
$PN"AE6"14;
"UPI0_RX_DN<5>"
$PN"AG8"15;
"UPI0_RX_DN<6>"
$PN"AJ6"16;
"UPI0_RX_DN<7>"
$PN"AL6"17;
"UPI0_RX_DN<8>"
$PN"AK7"18;
"UPI0_RX_DN<9>"
$PN"AM9"19;
"UPI0_RX_DN<10>"
$PN"AP7"36;
"UPI0_RX_DN<11>"
$PN"AR8"37;
"UPI0_RX_DN<12>"
$PN"AU10"38;
"UPI0_RX_DN<13>"
$PN"BA8"39;
"UPI0_RX_DN<14>"
$PN"BC6"40;
"UPI0_RX_DN<15>"
$PN"BD7"41;
"UPI0_RX_DN<16>"
$PN"AW8"42;
"UPI0_RX_DN<17>"
$PN"AY9"43;
"UPI0_RX_DN<18>"
$PN"BD9"44;
"UPI0_RX_DN<19>"
$PN"BB11"45;
%"TAP"
"1","(-5500,2075)","2","mstr_standard","I14";
;
CDS_LIB"mstr_standard"
BODY_TYPE"PLUMBING"
HDL_TAP"TRUE";
"B \NAC \NWC"4;
"S \NAC"
BN"10"36;
%"TAP"
"1","(-5500,2175)","2","mstr_standard","I16";
;
CDS_LIB"mstr_standard"
BODY_TYPE"PLUMBING"
HDL_TAP"TRUE";
"B \NAC \NWC"4;
"S \NAC"
BN"12"38;
%"TAP"
"1","(-5500,2375)","2","mstr_standard","I20";
;
CDS_LIB"mstr_standard"
BODY_TYPE"PLUMBING"
HDL_TAP"TRUE";
"B \NAC \NWC"4;
"S \NAC"
BN"16"42;
%"TAP"
"1","(-5500,2425)","2","mstr_standard","I21";
;
CDS_LIB"mstr_standard"
BODY_TYPE"PLUMBING"
HDL_TAP"TRUE";
"B \NAC \NWC"4;
"S \NAC"
BN"17"43;
%"TAP"
"1","(-5225,2725)","2","mstr_standard","I26";
;
CDS_LIB"mstr_standard"
BODY_TYPE"PLUMBING"
HDL_TAP"TRUE";
"B \NAC \NWC"3;
"S \NAC"
BN"2"22;
%"TAP"
"1","(-5225,1725)","2","mstr_standard","I27";
;
CDS_LIB"mstr_standard"
BODY_TYPE"PLUMBING"
HDL_TAP"TRUE";
"B \NAC \NWC"3;
"S \NAC"
BN"3"13;
%"TAP"
"1","(-5225,1775)","2","mstr_standard","I28";
;
CDS_LIB"mstr_standard"
BODY_TYPE"PLUMBING"
HDL_TAP"TRUE";
"B \NAC \NWC"3;
"S \NAC"
BN"4"14;
%"TAP"
"1","(-5225,3125)","2","mstr_standard","I34";
;
CDS_LIB"mstr_standard"
BODY_TYPE"PLUMBING"
HDL_TAP"TRUE";
"B \NAC \NWC"3;
"S \NAC"
BN"10"27;
%"TAP"
"1","(-5225,3225)","2","mstr_standard","I36";
;
CDS_LIB"mstr_standard"
BODY_TYPE"PLUMBING"
HDL_TAP"TRUE";
"B \NAC \NWC"3;
"S \NAC"
BN"12"29;
%"TAP"
"1","(-5225,3425)","2","mstr_standard","I40";
;
CDS_LIB"mstr_standard"
BODY_TYPE"PLUMBING"
HDL_TAP"TRUE";
"B \NAC \NWC"3;
"S \NAC"
BN"16"33;
%"TAP"
"1","(-5225,3475)","2","mstr_standard","I41";
;
CDS_LIB"mstr_standard"
BODY_TYPE"PLUMBING"
HDL_TAP"TRUE";
"B \NAC \NWC"3;
"S \NAC"
BN"17"34;
%"TAP"
"1","(-5225,2475)","2","mstr_standard","I42";
;
CDS_LIB"mstr_standard"
BODY_TYPE"PLUMBING"
HDL_TAP"TRUE";
"B \NAC \NWC"3;
"S \NAC"
BN"18"44;
%"TAP"
"1","(-5225,2525)","2","mstr_standard","I43";
;
CDS_LIB"mstr_standard"
BODY_TYPE"PLUMBING"
HDL_TAP"TRUE";
"B \NAC \NWC"3;
"S \NAC"
BN"19"45;
%"TAP"
"1","(-2575,1675)","0","mstr_standard","I46";
;
CDS_LIB"mstr_standard"
BODY_TYPE"PLUMBING"
HDL_TAP"TRUE";
"B \NAC \NWC"2;
"S \NAC"
BN"2"48;
%"TAP"
"1","(-2575,1725)","0","mstr_standard","I48";
;
CDS_LIB"mstr_standard"
BODY_TYPE"PLUMBING"
HDL_TAP"TRUE";
"B \NAC \NWC"2;
"S \NAC"
BN"3"49;
%"TAP"
"1","(-2575,2875)","0","mstr_standard","I49";
;
CDS_LIB"mstr_standard"
BODY_TYPE"PLUMBING"
HDL_TAP"TRUE";
"B \NAC \NWC"2;
"S \NAC"
BN"5"61;
%"TAP"
"1","(-5500,1675)","2","mstr_standard","I5";
;
CDS_LIB"mstr_standard"
BODY_TYPE"PLUMBING"
HDL_TAP"TRUE";
"B \NAC \NWC"4;
"S \NAC"
BN"2"12;
%"TAP"
"1","(-2575,1925)","0","mstr_standard","I51";
;
CDS_LIB"mstr_standard"
BODY_TYPE"PLUMBING"
HDL_TAP"TRUE";
"B \NAC \NWC"2;
"S \NAC"
BN"7"53;
%"TAP"
"1","(-2575,3125)","0","mstr_standard","I53";
;
CDS_LIB"mstr_standard"
BODY_TYPE"PLUMBING"
HDL_TAP"TRUE";
"B \NAC \NWC"2;
"S \NAC"
BN"10"66;
%"TAP"
"1","(-2575,2025)","0","mstr_standard","I54";
;
CDS_LIB"mstr_standard"
BODY_TYPE"PLUMBING"
HDL_TAP"TRUE";
"B \NAC \NWC"2;
"S \NAC"
BN"9"55;
%"TAP"
"1","(-2575,3325)","0","mstr_standard","I58";
;
CDS_LIB"mstr_standard"
BODY_TYPE"PLUMBING"
HDL_TAP"TRUE";
"B \NAC \NWC"2;
"S \NAC"
BN"14"69;
%"TAP"
"1","(-5500,2825)","2","mstr_standard","I6";
;
CDS_LIB"mstr_standard"
BODY_TYPE"PLUMBING"
HDL_TAP"TRUE";
"B \NAC \NWC"4;
"S \NAC"
BN"4"24;
%"TAP"
"1","(-2575,2425)","0","mstr_standard","I61";
;
CDS_LIB"mstr_standard"
BODY_TYPE"PLUMBING"
HDL_TAP"TRUE";
"B \NAC \NWC"2;
"S \NAC"
BN"17"82;
%"TAP"
"1","(-2575,2475)","0","mstr_standard","I62";
;
CDS_LIB"mstr_standard"
BODY_TYPE"PLUMBING"
HDL_TAP"TRUE";
"B \NAC \NWC"2;
"S \NAC"
BN"18"83;
%"TAP"
"1","(-2900,2725)","0","mstr_standard","I66";
;
CDS_LIB"mstr_standard"
BODY_TYPE"PLUMBING"
HDL_TAP"TRUE";
"B \NAC \NWC"1;
"S \NAC"
BN"2"58;
%"TAP"
"1","(-2900,2775)","0","mstr_standard","I67";
;
CDS_LIB"mstr_standard"
BODY_TYPE"PLUMBING"
HDL_TAP"TRUE";
"B \NAC \NWC"1;
"S \NAC"
BN"3"59;
%"TAP"
"1","(-2900,1825)","0","mstr_standard","I69";
;
CDS_LIB"mstr_standard"
BODY_TYPE"PLUMBING"
HDL_TAP"TRUE";
"B \NAC \NWC"1;
"S \NAC"
BN"5"51;
%"TAP"
"1","(-5500,2775)","2","mstr_standard","I7";
;
CDS_LIB"mstr_standard"
BODY_TYPE"PLUMBING"
HDL_TAP"TRUE";
"B \NAC \NWC"4;
"S \NAC"
BN"3"23;
%"TAP"
"1","(-2900,2975)","0","mstr_standard","I72";
;
CDS_LIB"mstr_standard"
BODY_TYPE"PLUMBING"
HDL_TAP"TRUE";
"B \NAC \NWC"1;
"S \NAC"
BN"7"63;
%"TAP"
"1","(-2900,3075)","0","mstr_standard","I73";
;
CDS_LIB"mstr_standard"
BODY_TYPE"PLUMBING"
HDL_TAP"TRUE";
"B \NAC \NWC"1;
"S \NAC"
BN"9"65;
%"TAP"
"1","(-2900,2075)","0","mstr_standard","I74";
;
CDS_LIB"mstr_standard"
BODY_TYPE"PLUMBING"
HDL_TAP"TRUE";
"B \NAC \NWC"1;
"S \NAC"
BN"10"75;
%"TAP"
"1","(-2900,2275)","0","mstr_standard","I78";
;
CDS_LIB"mstr_standard"
BODY_TYPE"PLUMBING"
HDL_TAP"TRUE";
"B \NAC \NWC"1;
"S \NAC"
BN"14"79;
%"TAP"
"1","(-2900,3475)","0","mstr_standard","I81";
;
CDS_LIB"mstr_standard"
BODY_TYPE"PLUMBING"
HDL_TAP"TRUE";
"B \NAC \NWC"1;
"S \NAC"
BN"17"72;
%"TAP"
"1","(-2900,3525)","0","mstr_standard","I83";
;
CDS_LIB"mstr_standard"
BODY_TYPE"PLUMBING"
HDL_TAP"TRUE";
"B \NAC \NWC"1;
"S \NAC"
BN"18"73;
%"TAP"
"1","(-5500,3525)","2","mstr_standard","I86";
;
CDS_LIB"mstr_standard"
BODY_TYPE"PLUMBING"
HDL_TAP"TRUE";
"B \NAC \NWC"4;
"S \NAC"
BN"18"35;
%"TAP"
"1","(-5500,3575)","2","mstr_standard","I87";
;
CDS_LIB"mstr_standard"
BODY_TYPE"PLUMBING"
HDL_TAP"TRUE";
"B \NAC \NWC"4;
"S \NAC"
BN"19"6;
%"TAP"
"1","(-5500,2625)","2","mstr_standard","I88";
;
CDS_LIB"mstr_standard"
BODY_TYPE"PLUMBING"
HDL_TAP"TRUE";
"B \NAC \NWC"4;
"S \NAC"
BN"0"20;
%"TAP"
"1","(-5500,2875)","2","mstr_standard","I89";
;
CDS_LIB"mstr_standard"
BODY_TYPE"PLUMBING"
HDL_TAP"TRUE";
"B \NAC \NWC"4;
"S \NAC"
BN"5"25;
%"TAP"
"1","(-5500,2925)","2","mstr_standard","I90";
;
CDS_LIB"mstr_standard"
BODY_TYPE"PLUMBING"
HDL_TAP"TRUE";
"B \NAC \NWC"4;
"S \NAC"
BN"6"7;
%"TAP"
"1","(-5500,2975)","2","mstr_standard","I91";
;
CDS_LIB"mstr_standard"
BODY_TYPE"PLUMBING"
HDL_TAP"TRUE";
"B \NAC \NWC"4;
"S \NAC"
BN"7"9;
%"TAP"
"1","(-5500,3025)","2","mstr_standard","I92";
;
CDS_LIB"mstr_standard"
BODY_TYPE"PLUMBING"
HDL_TAP"TRUE";
"B \NAC \NWC"4;
"S \NAC"
BN"8"8;
%"TAP"
"1","(-5500,3075)","2","mstr_standard","I93";
;
CDS_LIB"mstr_standard"
BODY_TYPE"PLUMBING"
HDL_TAP"TRUE";
"B \NAC \NWC"4;
"S \NAC"
BN"9"26;
%"TAP"
"1","(-5500,2225)","2","mstr_standard","I94";
;
CDS_LIB"mstr_standard"
BODY_TYPE"PLUMBING"
HDL_TAP"TRUE";
"B \NAC \NWC"4;
"S \NAC"
BN"13"39;
%"TAP"
"1","(-5500,3325)","2","mstr_standard","I95";
;
CDS_LIB"mstr_standard"
BODY_TYPE"PLUMBING"
HDL_TAP"TRUE";
"B \NAC \NWC"4;
"S \NAC"
BN"14"31;
%"TAP"
"1","(-5500,2325)","2","mstr_standard","I96";
;
CDS_LIB"mstr_standard"
BODY_TYPE"PLUMBING"
HDL_TAP"TRUE";
"B \NAC \NWC"4;
"S \NAC"
BN"15"41;
%"TAP"
"1","(-5500,3175)","2","mstr_standard","I97";
;
CDS_LIB"mstr_standard"
BODY_TYPE"PLUMBING"
HDL_TAP"TRUE";
"B \NAC \NWC"4;
"S \NAC"
BN"11"28;
%"TAP"
"1","(-5225,3375)","2","mstr_standard","I98";
;
CDS_LIB"mstr_standard"
BODY_TYPE"PLUMBING"
HDL_TAP"TRUE";
"B \NAC \NWC"3;
"S \NAC"
BN"15"32;
%"TAP"
"1","(-5225,2275)","2","mstr_standard","I99";
;
CDS_LIB"mstr_standard"
BODY_TYPE"PLUMBING"
HDL_TAP"TRUE";
"B \NAC \NWC"3;
"S \NAC"
BN"14"40;
END.
